# T6G (Grand Teton) — schematic netlist excerpt (pin names and nets, part order shuffled) for the footprints in the layout excerpt that follows; sources: Cadence DE-HDL packaged netlist, KiCad conversion of 04192023_DAF0TMB3IC0_F0TG_MB_C_brd_V02_OCP.brd

J38  SCONN168_ME1016810202011  IO  pkg CON_F168S2H7D_P0-6W2-95_LUH  page 131
  GND_A1  = GND
  GND_A2  = GND
  GND_A3  = GND
  GND_A4  = GND
  GND_A5  = GND
  GND_A6  = GND
  SMCLK  = SMB_OCP_SFF_3V3AUX_BUF_R_SCL
  SMDAT  = SMB_OCP_SFF_3V3AUX_BUF_R_SDA
  \smrst#\  = RST_SMB_OCP_SFF_N
  \prsnta#\  = OCP_SFF_PRSNTA_R_N
  \perst1#\  = RST_PERST1_OCP_SFF_N
  \prsntb2#\  = OCP_SFF_PRSNT2_R_N
  GND_A13  = GND
  REFCLKN1  = CLK_100M_CPU0_CLK03_DN
  REFCLKP1  = CLK_100M_CPU0_CLK03_DP
  GND_A16  = GND
  PERN0  = P5E_CPU0_G3_RX_DN<0>
  PERP0  = P5E_CPU0_G3_RX_DP<0>
  GND_A19  = GND
  PERN1  = P5E_CPU0_G3_RX_DN<1>
  PERP1  = P5E_CPU0_G3_RX_DP<1>
  GND_A22  = GND
  PERN2  = P5E_CPU0_G3_RX_DN<2>
  PERP2  = P5E_CPU0_G3_RX_DP<2>
  GND_A25  = GND
  PERN3  = P5E_CPU0_G3_RX_DN<3>
  PERP3  = P5E_CPU0_G3_RX_DP<3>
  GND_A28  = GND
  GND_A29  = GND
  PERN4  = P5E_CPU0_G3_RX_DN<4>
  PERP4  = P5E_CPU0_G3_RX_DP<4>
  GND_A32  = GND
  PERN5  = P5E_CPU0_G3_RX_DN<5>
  PERP5  = P5E_CPU0_G3_RX_DP<5>
  GND_A35  = GND
  PERN6  = P5E_CPU0_G3_RX_DN<6>
  PERP6  = P5E_CPU0_G3_RX_DP<6>
  GND_A38  = GND
  PERN7  = P5E_CPU0_G3_RX_DN<7>
  PERP7  = P5E_CPU0_G3_RX_DP<7>
  GND_A41  = GND
  \prsntb1#\  = OCP_SFF_PRSNT1_R_N
  GND_A43  = GND
  PERN8  = P5E_CPU0_G3_RX_DN<8>
  PERP8  = P5E_CPU0_G3_RX_DP<8>
  GND_A46  = GND
  PERN9  = P5E_CPU0_G3_RX_DN<9>
  PERP9  = P5E_CPU0_G3_RX_DP<9>
  GND_A49  = GND
  PERN10  = P5E_CPU0_G3_RX_DN<10>
  PERP10  = P5E_CPU0_G3_RX_DP<10>
  GND_A52  = GND
  PERN11  = P5E_CPU0_G3_RX_DN<11>
  PERP11  = P5E_CPU0_G3_RX_DP<11>
  GND_A55  = GND
  PERN12  = P5E_CPU0_G3_RX_DN<12>
  PERP12  = P5E_CPU0_G3_RX_DP<12>
  GND_A58  = GND
  PERN13  = P5E_CPU0_G3_RX_DN<13>
  PERP13  = P5E_CPU0_G3_RX_DP<13>
  GND_A61  = GND
  PERN14  = P5E_CPU0_G3_RX_DN<14>
  PERP14  = P5E_CPU0_G3_RX_DP<14>
  GND_A64  = GND
  PERN15  = P5E_CPU0_G3_RX_DN<15>
  PERP15  = P5E_CPU0_G3_RX_DP<15>
  GND_A67  = GND
  USB_DATN  = USB2_P11_DN
  USB_DATP  = USB2_P11_DP
  \pwrbrk0#\  = OCP_SFF_PWRBRK_N
  \+12v_edge_b1\  = P12V_OCP_SFF_R
  \+12v_edge_b2\  = P12V_OCP_SFF_R
  \+12v_edge_b3\  = P12V_OCP_SFF_R
  \+12v_edge_b4\  = P12V_OCP_SFF_R
  \+12v_edge_b5\  = P12V_OCP_SFF_R
  \+12v_edge_b6\  = P12V_OCP_SFF_R
  \bif0#\  = OCP_SFF_BIF0_R_N
  \bif1#\  = OCP_SFF_BIF1_R_N
  \bif2#\  = OCP_SFF_BIF2_R_N
  \perst0#\  = RST_PERST0_OCP_SFF_N
  \+3.3v_edge\  = P3V3_OCP_SFF
  AUX_PWR_EN  = OCP_SFF_AUX_PWR_EN_R
  GND_B13  = GND
  REFCLKN0  = CLK_100M_CPU0_CLK02_DN
  REFCLKP0  = CLK_100M_CPU0_CLK02_DP
  GND_B16  = GND
  PETN0  = P5E_CPU0_G3_TX_C_DP<0>
  PETP0  = P5E_CPU0_G3_TX_C_DN<0>
  GND_B19  = GND
  PETN1  = P5E_CPU0_G3_TX_C_DP<1>
  PETP1  = P5E_CPU0_G3_TX_C_DN<1>
  GND_B22  = GND
  PETN2  = P5E_CPU0_G3_TX_C_DP<2>
  PETP2  = P5E_CPU0_G3_TX_C_DN<2>
  GND_B25  = GND
  PETN3  = P5E_CPU0_G3_TX_C_DP<3>
  PETP3  = P5E_CPU0_G3_TX_C_DN<3>
  GND_B28  = GND
  GND_B29  = GND
  PETN4  = P5E_CPU0_G3_TX_C_DP<4>
  PETP4  = P5E_CPU0_G3_TX_C_DN<4>
  GND_B32  = GND
  PETN5  = P5E_CPU0_G3_TX_C_DP<5>
  PETP5  = P5E_CPU0_G3_TX_C_DN<5>
  GND_B35  = GND
  PETN6  = P5E_CPU0_G3_TX_C_DP<6>
  PETP6  = P5E_CPU0_G3_TX_C_DN<6>
  GND_B38  = GND
  PETN7  = P5E_CPU0_G3_TX_C_DP<7>
  PETP7  = P5E_CPU0_G3_TX_C_DN<7>
  GND_B41  = GND
  \prsntb0#\  = OCP_SFF_PRSNT0_R_N
  GND_B43  = GND
  PETN8  = P5E_CPU0_G3_TX_C_DP<8>
  PETP8  = P5E_CPU0_G3_TX_C_DN<8>
  GND_B46  = GND
  PETN9  = P5E_CPU0_G3_TX_C_DP<9>
  PETP9  = P5E_CPU0_G3_TX_C_DN<9>
  GND_B49  = GND
  PETN10  = P5E_CPU0_G3_TX_C_DP<10>
  PETP10  = P5E_CPU0_G3_TX_C_DN<10>
  GND_B52  = GND
  PETN11  = P5E_CPU0_G3_TX_C_DP<11>
  PETP11  = P5E_CPU0_G3_TX_C_DN<11>
  GND_B55  = GND
  PETN12  = P5E_CPU0_G3_TX_C_DP<12>
  PETP12  = P5E_CPU0_G3_TX_C_DN<12>
  GND_B58  = GND
  PETN13  = P5E_CPU0_G3_TX_C_DP<13>
  PETP13  = P5E_CPU0_G3_TX_C_DN<13>
  GND_B61  = GND
  PETN14  = P5E_CPU0_G3_TX_C_DP<14>
  PETP14  = P5E_CPU0_G3_TX_C_DN<14>
  GND_B64  = GND
  PETN15  = P5E_CPU0_G3_TX_C_DP<15>
  PETP15  = P5E_CPU0_G3_TX_C_DN<15>
  GND_B67  = GND
  RFU1_NC_B68  = TP_OCP_SFF_B68
  RFU1_NC_B69  = TP_OCP_SFF_B69
  \prsntb3#\  = OCP_SFF_PRSNT3_R_N
  G1  = GND
  G2  = GND
  G3  = GND
  G4  = GND
  G5  = GND
  \perst2#\  = RST_PERST2_OCP_SFF_N
  \perst3#\  = RST_PERST3_OCP_SFF_N
  \wake#\  = IRQ_LVC3_OCP_SFF_WAKE_N
  RBT_ARB_IN  = OCP_SFF_ISO1_RBT_ARB_IN
  RBT_ARB_OUT  = OCP_SFF_ISO2_RBT_ARB_OUT
  SLOT_ID1  = OCP_SFF_ID1
  RBT_TX_EN  = NCSI_OCP_SFF_TX_EN
  RBT_TXD1  = NCSI_OCP_SFF_TXD1
  RBT_TXD0  = NCSI_OCP_SFF_TXD0
  GND_OA10  = GND
  REFCLKN3  = CLK_100M_CPU0_CLK05_DN
  REFCLKP3  = CLK_100M_CPU0_CLK05_DP
  GND_OA13  = GND
  RBT_CLK_IN  = CLK_50M_NCSI_OCP_SFF_ISO
  NIC_PWR_GOOD  = FM_OCP_SFF_PWR_GOOD
  MAIN_PWR_EN  = OCP_SFF_MAIN_PWR_EN_R
  \ld#\  = SGPIO_OCP_SFF_LD_N
  DATA_IN  = SGPIO_OCP_SFF_DATAIN
  DATA_OUT  = SGPIO_OCP_SFF_DATAOUT
  CLK  = SGPIO_OCP_SFF_CLK
  SLOT_ID0  = OCP_SFF_ID0
  RBT_RXD1  = NCSI_OCP_SFF_RXD1
  RBT_RXD0  = NCSI_OCP_SFF_RXD0
  GND_OB10  = GND
  REFCLKN2  = CLK_100M_CPU0_CLK04_DN
  REFCLKP2  = CLK_100M_CPU0_CLK04_DP
  GND_OB13  = GND
  RBT_CRS_DV  = NCSI_OCP_SFF_CRS_DV

(kicad_pcb
	(version 20260206)
	(generator "pcbnew")
	(generator_version "10.0")
	(general
		(thickness 1.6)
		(legacy_teardrops no)
	)
	(paper "A4")
	(title_block
		(title "04192023_DAF0TMB3IC0_F0TG_MB_C_brd_V02_OCP.brd")
		(comment 1 "Grand Teton / footprint 2929 of 8354 (J38), pads 134-175 of 175")
	)
	(layers
		(0 "F.Cu" signal "TOP")
		(4 "In1.Cu" signal "GND")
		(6 "In2.Cu" signal "IN1")
		(8 "In3.Cu" signal "GND1")
		(10 "In4.Cu" signal "IN2")
		(12 "In5.Cu" signal "GND2")
		(14 "In6.Cu" signal "IN3")
		(16 "In7.Cu" signal "GND3")
		(18 "In8.Cu" signal "VCC")
		(20 "In9.Cu" signal "VCC1")
		(22 "In10.Cu" signal "GND4")
		(24 "In11.Cu" signal "IN4")
		(26 "In12.Cu" signal "GND5")
		(28 "In13.Cu" signal "IN5")
		(30 "In14.Cu" signal "GND6")
		(32 "In15.Cu" signal "IN6")
		(34 "In16.Cu" signal "GND7")
		(2 "B.Cu" signal "BOTTOM")
		(9 "F.Adhes" user "F.Adhesive")
		(11 "B.Adhes" user "B.Adhesive")
		(13 "F.Paste" user "Package Geometry/Pastemask Top")
		(15 "B.Paste" user "Package Geometry/Pastemask Bottom")
		(5 "F.SilkS" user "Ref Des/Silkscreen Top")
		(7 "B.SilkS" user "Ref Des/Silkscreen Bottom")
		(1 "F.Mask" user "Board Geometry/Soldermask Top")
		(3 "B.Mask" user "Board Geometry/Soldermask Bottom")
		(17 "Dwgs.User" user "User.Drawings")
		(19 "Cmts.User" user "User.Comments")
		(21 "Eco1.User" user "User.Eco1")
		(23 "Eco2.User" user "User.Eco2")
		(25 "Edge.Cuts" user "Board Geometry/Outline")
		(27 "Margin" user)
		(31 "F.CrtYd" user "Package Geometry/Place Bound Top")
		(29 "B.CrtYd" user "Package Geometry/Place Bound Bottom")
		(35 "F.Fab" user "Ref Des/Assembly Top")
		(33 "B.Fab" user "Ref Des/Assembly Bottom")
	)
	(footprint ""
		(layer "F.Cu")
		(at 421.901874 -5.569966 -90)
		(property "Reference" "J38"
			(at -8.103616 -20.50034 0)
			(unlocked yes)
			(layer "F.SilkS")
			(effects
				(font
					(size 0.7874 0.5842)
					(thickness 0.1524)
				)
				(justify left)
			)
		)
		(property "Value" ""
			(at 0 0 270)
			(layer "F.Fab")
			(effects
				(font
					(size 1.27 1.27)
				)
			)
		)
		(duplicate_pad_numbers_are_jumpers no)
		(pad "B62" smd rect
			(at -5.700014 25.854914 180)
			(size 0.381 1.4478)
			(layers "F.Cu" "F.Mask" "F.Paste")
			(net "P5E_CPU0_G3_TX_C_DP<14>")
		)
		(pad "B63" smd rect
			(at -5.700014 26.455116 180)
			(size 0.381 1.4478)
			(layers "F.Cu" "F.Mask" "F.Paste")
			(net "P5E_CPU0_G3_TX_C_DN<14>")
		)
		(pad "B64" smd rect
			(at -5.700014 27.055064 180)
			(size 0.381 1.4478)
			(layers "F.Cu" "F.Mask" "F.Paste")
			(net "GND")
		)
		(pad "B65" smd rect
			(at -5.700014 27.655012 180)
			(size 0.381 1.4478)
			(layers "F.Cu" "F.Mask" "F.Paste")
			(net "P5E_CPU0_G3_TX_C_DP<15>")
		)
		(pad "B66" smd rect
			(at -5.700014 28.25496 180)
			(size 0.381 1.4478)
			(layers "F.Cu" "F.Mask" "F.Paste")
			(net "P5E_CPU0_G3_TX_C_DN<15>")
		)
		(pad "B67" smd rect
			(at -5.700014 28.854908 180)
			(size 0.381 1.4478)
			(layers "F.Cu" "F.Mask" "F.Paste")
			(net "GND")
		)
		(pad "B68" smd rect
			(at -5.700014 29.45511 180)
			(size 0.381 1.4478)
			(layers "F.Cu" "F.Mask" "F.Paste")
			(net "TP_OCP_SFF_B68")
		)
		(pad "B69" smd rect
			(at -5.700014 30.055058 180)
			(size 0.381 1.4478)
			(layers "F.Cu" "F.Mask" "F.Paste")
			(net "TP_OCP_SFF_B69")
		)
		(pad "B70" smd rect
			(at -5.700014 30.655006 180)
			(size 0.381 1.4478)
			(layers "F.Cu" "F.Mask" "F.Paste")
			(net "OCP_SFF_PRSNT3_R_N")
		)
		(pad "G1" thru_hole circle
			(at 2.400046 -32.759904 180)
			(size 1.6256 1.6256)
			(drill 1.1176)
			(layers "*.Cu" "*.Mask")
			(remove_unused_layers no)
			(net "GND")
			(clearance 0)
		)
		(pad "G2" thru_hole circle
			(at 2.400046 -20.379944 180)
			(size 1.6256 1.6256)
			(drill 1.1176)
			(layers "*.Cu" "*.Mask")
			(remove_unused_layers no)
			(net "GND")
			(clearance 0)
		)
		(pad "G3" thru_hole circle
			(at 2.400046 0 180)
			(size 1.6256 1.6256)
			(drill 1.1176)
			(layers "*.Cu" "*.Mask")
			(remove_unused_layers no)
			(net "GND")
			(clearance 0)
		)
		(pad "G4" thru_hole circle
			(at 2.400046 12.5349 180)
			(size 1.6256 1.6256)
			(drill 1.1176)
			(layers "*.Cu" "*.Mask")
			(remove_unused_layers no)
			(net "GND")
			(clearance 0)
		)
		(pad "G5" thru_hole circle
			(at 2.400046 32.759904 180)
			(size 1.6256 1.6256)
			(drill 1.1176)
			(layers "*.Cu" "*.Mask")
			(remove_unused_layers no)
			(net "GND")
			(clearance 0)
		)
		(pad "OA1" smd rect
			(at -2.750058 -30.660086 180)
			(size 0.381 1.4478)
			(layers "F.Cu" "F.Mask" "F.Paste")
			(net "RST_PERST2_OCP_SFF_N")
		)
		(pad "OA2" smd rect
			(at -2.750058 -30.059884 180)
			(size 0.381 1.4478)
			(layers "F.Cu" "F.Mask" "F.Paste")
			(net "RST_PERST3_OCP_SFF_N")
		)
		(pad "OA3" smd rect
			(at -2.750058 -29.459936 180)
			(size 0.381 1.4478)
			(layers "F.Cu" "F.Mask" "F.Paste")
			(net "IRQ_LVC3_OCP_SFF_WAKE_N")
		)
		(pad "OA4" smd rect
			(at -2.750058 -28.859988 180)
			(size 0.381 1.4478)
			(layers "F.Cu" "F.Mask" "F.Paste")
			(net "OCP_SFF_ISO1_RBT_ARB_IN")
		)
		(pad "OA5" smd rect
			(at -2.750058 -28.26004 180)
			(size 0.381 1.4478)
			(layers "F.Cu" "F.Mask" "F.Paste")
			(net "OCP_SFF_ISO2_RBT_ARB_OUT")
		)
		(pad "OA6" smd rect
			(at -2.750058 -27.660092 180)
			(size 0.381 1.4478)
			(layers "F.Cu" "F.Mask" "F.Paste")
			(net "OCP_SFF_ID1")
		)
		(pad "OA7" smd rect
			(at -2.750058 -27.05989 180)
			(size 0.381 1.4478)
			(layers "F.Cu" "F.Mask" "F.Paste")
			(net "NCSI_OCP_SFF_TX_EN")
		)
		(pad "OA8" smd rect
			(at -2.750058 -26.459942 180)
			(size 0.381 1.4478)
			(layers "F.Cu" "F.Mask" "F.Paste")
			(net "NCSI_OCP_SFF_TXD1")
		)
		(pad "OA9" smd rect
			(at -2.750058 -25.859994 180)
			(size 0.381 1.4478)
			(layers "F.Cu" "F.Mask" "F.Paste")
			(net "NCSI_OCP_SFF_TXD0")
		)
		(pad "OA10" smd rect
			(at -2.750058 -25.260046 180)
			(size 0.381 1.4478)
			(layers "F.Cu" "F.Mask" "F.Paste")
			(net "GND")
		)
		(pad "OA11" smd rect
			(at -2.750058 -24.660098 180)
			(size 0.381 1.4478)
			(layers "F.Cu" "F.Mask" "F.Paste")
			(net "CLK_100M_CPU0_CLK05_DN")
		)
		(pad "OA12" smd rect
			(at -2.750058 -24.059896 180)
			(size 0.381 1.4478)
			(layers "F.Cu" "F.Mask" "F.Paste")
			(net "CLK_100M_CPU0_CLK05_DP")
		)
		(pad "OA13" smd rect
			(at -2.750058 -23.459948 180)
			(size 0.381 1.4478)
			(layers "F.Cu" "F.Mask" "F.Paste")
			(net "GND")
		)
		(pad "OA14" smd rect
			(at -2.750058 -22.86 180)
			(size 0.381 1.4478)
			(layers "F.Cu" "F.Mask" "F.Paste")
			(net "CLK_50M_NCSI_OCP_SFF_ISO")
		)
		(pad "OB1" smd rect
			(at -5.700014 -30.660086 180)
			(size 0.381 1.4478)
			(layers "F.Cu" "F.Mask" "F.Paste")
			(net "FM_OCP_SFF_PWR_GOOD")
		)
		(pad "OB2" smd rect
			(at -5.700014 -30.059884 180)
			(size 0.381 1.4478)
			(layers "F.Cu" "F.Mask" "F.Paste")
			(net "OCP_SFF_MAIN_PWR_EN_R")
		)
		(pad "OB3" smd rect
			(at -5.700014 -29.459936 180)
			(size 0.381 1.4478)
			(layers "F.Cu" "F.Mask" "F.Paste")
			(net "SGPIO_OCP_SFF_LD_N")
		)
		(pad "OB4" smd rect
			(at -5.700014 -28.859988 180)
			(size 0.381 1.4478)
			(layers "F.Cu" "F.Mask" "F.Paste")
			(net "SGPIO_OCP_SFF_DATAIN")
		)
		(pad "OB5" smd rect
			(at -5.700014 -28.26004 180)
			(size 0.381 1.4478)
			(layers "F.Cu" "F.Mask" "F.Paste")
			(net "SGPIO_OCP_SFF_DATAOUT")
		)
		(pad "OB6" smd rect
			(at -5.700014 -27.660092 180)
			(size 0.381 1.4478)
			(layers "F.Cu" "F.Mask" "F.Paste")
			(net "SGPIO_OCP_SFF_CLK")
		)
		(pad "OB7" smd rect
			(at -5.700014 -27.05989 180)
			(size 0.381 1.4478)
			(layers "F.Cu" "F.Mask" "F.Paste")
			(net "OCP_SFF_ID0")
		)
		(pad "OB8" smd rect
			(at -5.700014 -26.459942 180)
			(size 0.381 1.4478)
			(layers "F.Cu" "F.Mask" "F.Paste")
			(net "NCSI_OCP_SFF_RXD1")
		)
		(pad "OB9" smd rect
			(at -5.700014 -25.859994 180)
			(size 0.381 1.4478)
			(layers "F.Cu" "F.Mask" "F.Paste")
			(net "NCSI_OCP_SFF_RXD0")
		)
		(pad "OB10" smd rect
			(at -5.700014 -25.260046 180)
			(size 0.381 1.4478)
			(layers "F.Cu" "F.Mask" "F.Paste")
			(net "GND")
		)
		(pad "OB11" smd rect
			(at -5.700014 -24.660098 180)
			(size 0.381 1.4478)
			(layers "F.Cu" "F.Mask" "F.Paste")
			(net "CLK_100M_CPU0_CLK04_DN")
		)
		(pad "OB12" smd rect
			(at -5.700014 -24.059896 180)
			(size 0.381 1.4478)
			(layers "F.Cu" "F.Mask" "F.Paste")
			(net "CLK_100M_CPU0_CLK04_DP")
		)
		(pad "OB13" smd rect
			(at -5.700014 -23.459948 180)
			(size 0.381 1.4478)
			(layers "F.Cu" "F.Mask" "F.Paste")
			(net "GND")
		)
		(pad "OB14" smd rect
			(at -5.700014 -22.86 180)
			(size 0.381 1.4478)
			(layers "F.Cu" "F.Mask" "F.Paste")
			(net "NCSI_OCP_SFF_CRS_DV")
		)
	)
)
